# S9S_MB_2U (Grand Teton) — schematic netlist excerpt (pin names and nets, part order shuffled) for the footprints in the layout excerpt that follows; sources: Cadence DE-HDL packaged netlist, KiCad conversion of 03242023_DA0F0TMBIJ0_F0T_Motherboard_J_brd_V01_OCP.brd

J4  SCONN288_ADR50017P087CC  SCONN288_ADR50017-P087CC IO  pkg DDR288S_1-1VXB  page 85
  VIN_BULK0  = P12V_S3_AUX_CPU0_NVDIMM
  RFU0  = TP_CHB_CPU0_DIMM2_FRU_0
  VIN_MGMT  = P3V3_AUX
  HSCL  = I3C_SPD_DDRABCD_CPU0_LVC1_SCL_3
  HSDA  = I3C_SPD_DDRABCD_CPU0_LVC1_SDA
  VSS0  = GND
  DQ0_A  = M_B_CPU0_SA_DQ<0>
  VSS1  = GND
  DQ1_A  = M_B_CPU0_SA_DQ<1>
  VSS2  = GND
  DQS0_A_T  = M_B_CPU0_SA_DQS_DP<0>
  DQS0_A_C  = M_B_CPU0_SA_DQS_DN<0>
  VSS3  = GND
  DQ4_A  = M_B_CPU0_SA_DQ<4>
  VSS4  = GND
  DQ5_A  = M_B_CPU0_SA_DQ<5>
  VSS5  = GND
  DQ8_A  = M_B_CPU0_SA_DQ<8>
  VSS6  = GND
  DQ9_A  = M_B_CPU0_SA_DQ<9>
  VSS7  = GND
  DQS1_A_T  = M_B_CPU0_SA_DQS_DP<1>
  DQS1_A_C  = M_B_CPU0_SA_DQS_DN<1>
  VSS8  = GND
  DQ12_A  = M_B_CPU0_SA_DQ<12>
  VSS9  = GND
  DQ13_A  = M_B_CPU0_SA_DQ<13>
  VSS10  = GND
  DQ16_A  = M_B_CPU0_SA_DQ<16>
  VSS11  = GND
  DQ17_A  = M_B_CPU0_SA_DQ<17>
  VSS12  = GND
  DQS2_A_T  = M_B_CPU0_SA_DQS_DP<2>
  DQS2_A_C  = M_B_CPU0_SA_DQS_DN<2>
  VSS13  = GND
  DQ20_A  = M_B_CPU0_SA_DQ<20>
  VSS14  = GND
  DQ21_A  = M_B_CPU0_SA_DQ<21>
  VSS15  = GND
  DQ24_A  = M_B_CPU0_SA_DQ<24>
  VSS16  = GND
  DQ25_A  = M_B_CPU0_SA_DQ<25>
  VSS17  = GND
  DQS3_A_T  = M_B_CPU0_SA_DQS_DP<3>
  DQS3_A_C  = M_B_CPU0_SA_DQS_DN<3>
  VSS18  = GND
  DQ28_A  = M_B_CPU0_SA_DQ<28>
  VSS19  = GND
  DQ29_A  = M_B_CPU0_SA_DQ<29>
  VSS20  = GND
  CB0_A  = M_B_CPU0_SA_CB<0>
  VSS21  = GND
  CB1_A  = M_B_CPU0_SA_CB<1>
  VSS22  = GND
  DQS4_A_T  = M_B_CPU0_SA_DQS_DP<4>
  DQS4_A_C  = M_B_CPU0_SA_DQS_DN<4>
  VSS23  = GND
  CB4_A  = M_B_CPU0_SA_CB<4>
  VSS24  = GND
  CB5_A  = M_B_CPU0_SA_CB<5>
  VSS25  = GND
  ALERT_N  = M_B_CPU0_ALERT_N
  VSS26  = GND
  CS0_A_N  = M_B_CPU0_SA_CS_N<2>
  VSS27  = GND
  CA0_A  = M_B_CPU0_SA_CA<0>
  VSS28  = GND
  CA2_A  = M_B_CPU0_SA_CA<2>
  VSS29  = GND
  CA4_A  = M_B_CPU0_SA_CA<4>
  VSS30  = GND
  CA6_A  = M_B_CPU0_SA_CA<6>
  VSS31  = GND
  PAR_A  = M_B_CPU0_SA_PAR
  VSS32  = GND
  CA0_B  = M_B_CPU0_SB_CA<0>
  VSS33  = GND
  CA2_B  = M_B_CPU0_SB_CA<2>
  VSS34  = GND
  CA4_B  = M_B_CPU0_SB_CA<4>
  VSS35  = GND
  CA6_B  = M_B_CPU0_SB_CA<6>
  VSS36  = GND
  CS0_B_N  = M_B_CPU0_SB_CS_N<2>
  VSS37  = GND
  \lbd||rsp_a_n\  = M_B_CPU0_SA_RSP<1>
  \lbs||rsp_b_n\  = M_B_CPU0_SB_RSP<1>
  VSS38  = GND
  CB4_B  = M_B_CPU0_SB_CB<4>
  VSS39  = GND
  CB5_B  = M_B_CPU0_SB_CB<5>
  VSS40  = GND
  \dqs9_b_t||tdqs9_b_t||dbi4_b_n\  = M_B_CPU0_SB_DQS_DP<9>
  \dqs9_b_c||tdqs9_b_c\  = M_B_CPU0_SB_DQS_DN<9>
  VSS41  = GND
  CB0_B  = M_B_CPU0_SB_CB<0>
  VSS42  = GND
  CB1_B  = M_B_CPU0_SB_CB<1>
  VSS43  = GND
  DQ0_B  = M_B_CPU0_SB_DQ<0>
  VSS44  = GND
  DQ1_B  = M_B_CPU0_SB_DQ<1>
  VSS45  = GND
  DQS0_B_T  = M_B_CPU0_SB_DQS_DP<0>
  DQS0_B_C  = M_B_CPU0_SB_DQS_DN<0>
  VSS46  = GND
  DQ4_B  = M_B_CPU0_SB_DQ<4>
  VSS47  = GND
  DQ5_B  = M_B_CPU0_SB_DQ<5>
  VSS48  = GND
  DQ8_B  = M_B_CPU0_SB_DQ<8>
  VSS49  = GND
  DQ9_B  = M_B_CPU0_SB_DQ<9>
  VSS50  = GND
  DQS1_B_T  = M_B_CPU0_SB_DQS_DP<1>
  DQS1_B_C  = M_B_CPU0_SB_DQS_DN<1>
  VSS51  = GND
  DQ12_B  = M_B_CPU0_SB_DQ<12>
  VSS52  = GND
  DQ13_B  = M_B_CPU0_SB_DQ<13>
  VSS53  = GND
  DQ16_B  = M_B_CPU0_SB_DQ<16>
  VSS54  = GND
  DQ17_B  = M_B_CPU0_SB_DQ<17>
  VSS55  = GND
  DQS2_B_T  = M_B_CPU0_SB_DQS_DP<2>
  DQS2_B_C  = M_B_CPU0_SB_DQS_DN<2>
  VSS56  = GND
  DQ20_B  = M_B_CPU0_SB_DQ<20>
  VSS57  = GND
  DQ21_B  = M_B_CPU0_SB_DQ<21>
  VSS58  = GND
  DQ24_B  = M_B_CPU0_SB_DQ<24>
  VSS59  = GND
  DQ25_B  = M_B_CPU0_SB_DQ<25>
  VSS60  = GND
  DQS3_B_T  = M_B_CPU0_SB_DQS_DP<3>
  DQS3_B_C  = M_B_CPU0_SB_DQS_DN<3>
  VSS61  = GND
  DQ28_B  = M_B_CPU0_SB_DQ<28>
  VSS62  = GND
  DQ29_B  = M_B_CPU0_SB_DQ<29>
  VSS63  = GND
  RFU1  = TP_CHB_CPU0_DIMM2_FRU_1
  VIN_BULK1  = P12V_S3_AUX_CPU0_NVDIMM
  VIN_BULK2  = P12V_S3_AUX_CPU0_NVDIMM
  \pwr_good||fail_n\  = PWRGD_CHB_CPU0_DIMM2
  HSA  = PD_CHB_CPU0_DIMM2_SAA
  RFU2  = TP_CHB_CPU0_DIMM2_FRU_2
  RFU3  = TP_CHB_CPU0_DIMM2_FRU_3
  VSS64  = GND
  DQ2_A  = M_B_CPU0_SA_DQ<2>
  VSS65  = GND
  DQ3_A  = M_B_CPU0_SA_DQ<3>
  VSS66  = GND
  \dqs5_a_c||tdqs5_a_c||dqs5_a_t||tdqs5_a_t\  = M_B_CPU0_SA_DQS_DN<5>
  \dqs5_a_t||tdqs5_a_t\  = M_B_CPU0_SA_DQS_DP<5>
  VSS67  = GND
  DQ6_A  = M_B_CPU0_SA_DQ<6>
  VSS68  = GND
  DQ7_A  = M_B_CPU0_SA_DQ<7>
  VSS69  = GND
  DQ10_A  = M_B_CPU0_SA_DQ<10>
  VSS70  = GND
  DQ11_A  = M_B_CPU0_SA_DQ<11>
  VSS71  = GND
  \dqs6_a_c||tdqs6_a_c||dqs6_a_t||tdqs6_a_t\  = M_B_CPU0_SA_DQS_DN<6>
  \dqs6_a_t||tdqs6_a_t\  = M_B_CPU0_SA_DQS_DP<6>
  VSS72  = GND
  DQ14_A  = M_B_CPU0_SA_DQ<14>
  VSS73  = GND
  DQ15_A  = M_B_CPU0_SA_DQ<15>
  VSS74  = GND
  DQ18_A  = M_B_CPU0_SA_DQ<18>
  VSS75  = GND
  DQ19_A  = M_B_CPU0_SA_DQ<19>
  VSS76  = GND
  \dqs7_a_c||tdqs7_a_c\  = M_B_CPU0_SA_DQS_DN<7>
  \dqs7_a_t||tdqs7_a_t\  = M_B_CPU0_SA_DQS_DP<7>
  VSS77  = GND
  DQ22_A  = M_B_CPU0_SA_DQ<22>
  VSS78  = GND
  DQ23_A  = M_B_CPU0_SA_DQ<23>
  VSS79  = GND
  DQ26_A  = M_B_CPU0_SA_DQ<26>
  VSS80  = GND
  DQ27_A  = M_B_CPU0_SA_DQ<27>
  VSS81  = GND
  \dqs8_a_c||tdqs8_a_c\  = M_B_CPU0_SA_DQS_DN<8>
  \dqs8_a_t||tdqs8_a_t\  = M_B_CPU0_SA_DQS_DP<8>
  VSS82  = GND
  DQ30_A  = M_B_CPU0_SA_DQ<30>
  VSS83  = GND
  DQ31_A  = M_B_CPU0_SA_DQ<31>
  VSS84  = GND
  CB2_A  = M_B_CPU0_SA_CB<2>
  VSS85  = GND
  CB3_A  = M_B_CPU0_SA_CB<3>
  VSS86  = GND
  \dqs9_a_c||tdqs9_a_c\  = M_B_CPU0_SA_DQS_DN<9>
  \dqs9_a_t||tdqs9_a_t\  = M_B_CPU0_SA_DQS_DP<9>
  VSS87  = GND
  CB6_A  = M_B_CPU0_SA_CB<6>
  VSS88  = GND
  CB7_A  = M_B_CPU0_SA_CB<7>
  VSS89  = GND
  RESET_N  = RST_M_AB_CPU0_FPGA_N
  VSS90  = GND
  CS1_A_N  = M_B_CPU0_SA_CS_N<3>
  VSS91  = GND
  CA1_A  = M_B_CPU0_SA_CA<1>
  VSS92  = GND
  CA3_A  = M_B_CPU0_SA_CA<3>
  VSS93  = GND
  CA5_A  = M_B_CPU0_SA_CA<5>
  VSS94  = GND
  CK_T  = M_B_CPU0_CLK_DP<1>
  CK_C  = M_B_CPU0_CLK_DN<1>
  VSS95  = GND
  RFU4  = TP_CHB_CPU0_DIMM2_FRU_4
  CA1_B  = M_B_CPU0_SB_CA<1>
  VSS96  = GND
  CA3_B  = M_B_CPU0_SB_CA<3>
  VSS97  = GND
  CA5_B  = M_B_CPU0_SB_CA<5>
  VSS98  = GND
  PAR_B  = M_B_CPU0_SB_PAR
  VSS99  = GND
  CS1_B_N  = M_B_CPU0_SB_CS_N<3>
  VSS100  = GND
  RFU5  = TP_CHB_CPU0_DIMM2_FRU_5
  RFU6  = TP_CHB_CPU0_DIMM2_FRU_6
  VSS101  = GND
  CB6_B  = M_B_CPU0_SB_CB<6>
  VSS102  = GND
  CB7_B  = M_B_CPU0_SB_CB<7>
  VSS103  = GND
  DQS4_B_C  = M_B_CPU0_SB_DQS_DN<4>
  DQS4_B_T  = M_B_CPU0_SB_DQS_DP<4>
  VSS104  = GND
  CB2_B  = M_B_CPU0_SB_CB<2>
  VSS105  = GND
  CB3_B  = M_B_CPU0_SB_CB<3>
  VSS106  = GND
  DQ2_B  = M_B_CPU0_SB_DQ<2>
  VSS107  = GND
  DQ3_B  = M_B_CPU0_SB_DQ<3>
  VSS108  = GND
  \dqs5_b_c||tdqs5_b_c\  = M_B_CPU0_SB_DQS_DN<5>
  \dqs5_b_t||tdqs5_b_t\  = M_B_CPU0_SB_DQS_DP<5>
  VSS109  = GND
  DQ6_B  = M_B_CPU0_SB_DQ<6>
  VSS110  = GND
  DQ7_B  = M_B_CPU0_SB_DQ<7>
  VSS111  = GND
  DQ10_B  = M_B_CPU0_SB_DQ<10>
  VSS112  = GND
  DQ11_B  = M_B_CPU0_SB_DQ<11>
  VSS113  = GND
  \dqs6_b_c||tdqs6_b_c\  = M_B_CPU0_SB_DQS_DN<6>
  \dqs6_b_t||tdqs6_b_t\  = M_B_CPU0_SB_DQS_DP<6>
  VSS114  = GND
  DQ14_B  = M_B_CPU0_SB_DQ<14>
  VSS115  = GND
  DQ15_B  = M_B_CPU0_SB_DQ<15>
  VSS116  = GND
  DQ18_B  = M_B_CPU0_SB_DQ<18>
  VSS117  = GND
  DQ19_B  = M_B_CPU0_SB_DQ<19>
  VSS118  = GND
  \dqs7_b_c||tdqs7_b_c\  = M_B_CPU0_SB_DQS_DN<7>
  \dqs7_b_t||tdqs7_b_t\  = M_B_CPU0_SB_DQS_DP<7>
  VSS119  = GND
  DQ22_B  = M_B_CPU0_SB_DQ<22>
  VSS120  = GND
  DQ23_B  = M_B_CPU0_SB_DQ<23>
  VSS121  = GND
  DQ26_B  = M_B_CPU0_SB_DQ<26>
  VSS122  = GND
  DQ27_B  = M_B_CPU0_SB_DQ<27>
  VSS123  = GND
  \dqs8_b_c||tdqs8_b_c\  = M_B_CPU0_SB_DQS_DN<8>
  \dqs8_b_t||tdqs8_b_t\  = M_B_CPU0_SB_DQS_DP<8>
  VSS124  = GND
  DQ30_B  = M_B_CPU0_SB_DQ<30>
  VSS125  = GND
  DQ31_B  = M_B_CPU0_SB_DQ<31>
  VSS126  = GND
  G1  = GND
  G2  = GND
  G3  = GND

(kicad_pcb
	(version 20260206)
	(generator "pcbnew")
	(generator_version "10.0")
	(general
		(thickness 1.6)
		(legacy_teardrops no)
	)
	(paper "A4")
	(title_block
		(title "03242023_DA0F0TMBIJ0_F0T_Motherboard_J_brd_V01_OCP.brd")
		(comment 1 "Grand Teton / footprint 1229 of 6105 (J4), pads 229-274 of 291")
	)
	(layers
		(0 "F.Cu" signal "TOP")
		(4 "In1.Cu" signal "GND")
		(6 "In2.Cu" signal "IN1")
		(8 "In3.Cu" signal "GND1")
		(10 "In4.Cu" signal "IN2")
		(12 "In5.Cu" signal "GND2")
		(14 "In6.Cu" signal "IN3")
		(16 "In7.Cu" signal "GND3")
		(18 "In8.Cu" signal "VCC")
		(20 "In9.Cu" signal "VCC1")
		(22 "In10.Cu" signal "GND4")
		(24 "In11.Cu" signal "IN4")
		(26 "In12.Cu" signal "GND5")
		(28 "In13.Cu" signal "IN5")
		(30 "In14.Cu" signal "GND6")
		(32 "In15.Cu" signal "IN6")
		(34 "In16.Cu" signal "GND7")
		(2 "B.Cu" signal "BOTTOM")
		(9 "F.Adhes" user "F.Adhesive")
		(11 "B.Adhes" user "B.Adhesive")
		(13 "F.Paste" user "Package Geometry/Pastemask Top")
		(15 "B.Paste" user "Package Geometry/Pastemask Bottom")
		(5 "F.SilkS" user "Ref Des/Silkscreen Top")
		(7 "B.SilkS" user "Ref Des/Silkscreen Bottom")
		(1 "F.Mask" user "Board Geometry/Soldermask Top")
		(3 "B.Mask" user "Board Geometry/Soldermask Bottom")
		(17 "Dwgs.User" user "User.Drawings")
		(19 "Cmts.User" user "User.Comments")
		(21 "Eco1.User" user "User.Eco1")
		(23 "Eco2.User" user "User.Eco2")
		(25 "Edge.Cuts" user "Board Geometry/Outline")
		(27 "Margin" user)
		(31 "F.CrtYd" user "Package Geometry/Place Bound Top")
		(29 "B.CrtYd" user "Package Geometry/Place Bound Bottom")
		(35 "F.Fab" user "Ref Des/Assembly Top")
		(33 "B.Fab" user "Ref Des/Assembly Bottom")
	)
	(footprint ""
		(layer "F.Cu")
		(at 295.849548 -258.091686)
		(property "Reference" "J4"
			(at -3.683 -81.702148 0)
			(unlocked yes)
			(layer "F.SilkS")
			(effects
				(font
					(size 0.7874 0.5842)
					(thickness 0.1524)
				)
				(justify left)
			)
		)
		(property "Value" ""
			(at 0 0 0)
			(layer "F.Fab")
			(effects
				(font
					(size 1.27 1.27)
				)
			)
		)
		(duplicate_pad_numbers_are_jumpers no)
		(pad "229" smd rect
			(at 2.050034 13.17498 270)
			(size 0.519938 1.4986)
			(layers "F.Cu" "F.Mask" "F.Paste")
			(net "M_B_CPU0_SB_CS_N<3>")
		)
		(pad "230" smd rect
			(at 2.050034 14.025118 270)
			(size 0.519938 1.4986)
			(layers "F.Cu" "F.Mask" "F.Paste")
			(net "GND")
		)
		(pad "231" smd rect
			(at 2.050034 14.875002 270)
			(size 0.519938 1.4986)
			(layers "F.Cu" "F.Mask" "F.Paste")
			(net "TP_CHB_CPU0_DIMM2_FRU_5")
		)
		(pad "232" smd rect
			(at 2.050034 15.724886 270)
			(size 0.519938 1.4986)
			(layers "F.Cu" "F.Mask" "F.Paste")
			(net "TP_CHB_CPU0_DIMM2_FRU_6")
		)
		(pad "233" smd rect
			(at 2.050034 16.575024 270)
			(size 0.519938 1.4986)
			(layers "F.Cu" "F.Mask" "F.Paste")
			(net "GND")
		)
		(pad "234" smd rect
			(at 2.050034 17.424908 270)
			(size 0.519938 1.4986)
			(layers "F.Cu" "F.Mask" "F.Paste")
			(net "M_B_CPU0_SB_CB<6>")
		)
		(pad "235" smd rect
			(at 2.050034 18.275046 270)
			(size 0.519938 1.4986)
			(layers "F.Cu" "F.Mask" "F.Paste")
			(net "GND")
		)
		(pad "236" smd rect
			(at 2.050034 19.12493 270)
			(size 0.519938 1.4986)
			(layers "F.Cu" "F.Mask" "F.Paste")
			(net "M_B_CPU0_SB_CB<7>")
		)
		(pad "237" smd rect
			(at 2.050034 19.975068 270)
			(size 0.519938 1.4986)
			(layers "F.Cu" "F.Mask" "F.Paste")
			(net "GND")
		)
		(pad "238" smd rect
			(at 2.050034 20.824952 270)
			(size 0.519938 1.4986)
			(layers "F.Cu" "F.Mask" "F.Paste")
			(net "M_B_CPU0_SB_DQS_DN<4>")
		)
		(pad "239" smd rect
			(at 2.050034 21.67509 270)
			(size 0.519938 1.4986)
			(layers "F.Cu" "F.Mask" "F.Paste")
			(net "M_B_CPU0_SB_DQS_DP<4>")
		)
		(pad "240" smd rect
			(at 2.050034 22.524974 270)
			(size 0.519938 1.4986)
			(layers "F.Cu" "F.Mask" "F.Paste")
			(net "GND")
		)
		(pad "241" smd rect
			(at 2.050034 23.375112 270)
			(size 0.519938 1.4986)
			(layers "F.Cu" "F.Mask" "F.Paste")
			(net "M_B_CPU0_SB_CB<2>")
		)
		(pad "242" smd rect
			(at 2.050034 24.224996 270)
			(size 0.519938 1.4986)
			(layers "F.Cu" "F.Mask" "F.Paste")
			(net "GND")
		)
		(pad "243" smd rect
			(at 2.050034 25.07488 270)
			(size 0.519938 1.4986)
			(layers "F.Cu" "F.Mask" "F.Paste")
			(net "M_B_CPU0_SB_CB<3>")
		)
		(pad "244" smd rect
			(at 2.050034 25.925018 270)
			(size 0.519938 1.4986)
			(layers "F.Cu" "F.Mask" "F.Paste")
			(net "GND")
		)
		(pad "245" smd rect
			(at 2.050034 26.774902 270)
			(size 0.519938 1.4986)
			(layers "F.Cu" "F.Mask" "F.Paste")
			(net "M_B_CPU0_SB_DQ<2>")
		)
		(pad "246" smd rect
			(at 2.050034 27.62504 270)
			(size 0.519938 1.4986)
			(layers "F.Cu" "F.Mask" "F.Paste")
			(net "GND")
		)
		(pad "247" smd rect
			(at 2.050034 28.474924 270)
			(size 0.519938 1.4986)
			(layers "F.Cu" "F.Mask" "F.Paste")
			(net "M_B_CPU0_SB_DQ<3>")
		)
		(pad "248" smd rect
			(at 2.050034 29.325062 270)
			(size 0.519938 1.4986)
			(layers "F.Cu" "F.Mask" "F.Paste")
			(net "GND")
		)
		(pad "249" smd rect
			(at 2.050034 30.174946 270)
			(size 0.519938 1.4986)
			(layers "F.Cu" "F.Mask" "F.Paste")
			(net "M_B_CPU0_SB_DQS_DN<5>")
		)
		(pad "250" smd rect
			(at 2.050034 31.025084 270)
			(size 0.519938 1.4986)
			(layers "F.Cu" "F.Mask" "F.Paste")
			(net "M_B_CPU0_SB_DQS_DP<5>")
		)
		(pad "251" smd rect
			(at 2.050034 31.874968 270)
			(size 0.519938 1.4986)
			(layers "F.Cu" "F.Mask" "F.Paste")
			(net "GND")
		)
		(pad "252" smd rect
			(at 2.050034 32.725106 270)
			(size 0.519938 1.4986)
			(layers "F.Cu" "F.Mask" "F.Paste")
			(net "M_B_CPU0_SB_DQ<6>")
		)
		(pad "253" smd rect
			(at 2.050034 33.57499 270)
			(size 0.519938 1.4986)
			(layers "F.Cu" "F.Mask" "F.Paste")
			(net "GND")
		)
		(pad "254" smd rect
			(at 2.050034 34.425128 270)
			(size 0.519938 1.4986)
			(layers "F.Cu" "F.Mask" "F.Paste")
			(net "M_B_CPU0_SB_DQ<7>")
		)
		(pad "255" smd rect
			(at 2.050034 35.275012 270)
			(size 0.519938 1.4986)
			(layers "F.Cu" "F.Mask" "F.Paste")
			(net "GND")
		)
		(pad "256" smd rect
			(at 2.050034 36.124896 270)
			(size 0.519938 1.4986)
			(layers "F.Cu" "F.Mask" "F.Paste")
			(net "M_B_CPU0_SB_DQ<10>")
		)
		(pad "257" smd rect
			(at 2.050034 36.975034 270)
			(size 0.519938 1.4986)
			(layers "F.Cu" "F.Mask" "F.Paste")
			(net "GND")
		)
		(pad "258" smd rect
			(at 2.050034 37.824918 270)
			(size 0.519938 1.4986)
			(layers "F.Cu" "F.Mask" "F.Paste")
			(net "M_B_CPU0_SB_DQ<11>")
		)
		(pad "259" smd rect
			(at 2.050034 38.675056 270)
			(size 0.519938 1.4986)
			(layers "F.Cu" "F.Mask" "F.Paste")
			(net "GND")
		)
		(pad "260" smd rect
			(at 2.050034 39.52494 270)
			(size 0.519938 1.4986)
			(layers "F.Cu" "F.Mask" "F.Paste")
			(net "M_B_CPU0_SB_DQS_DN<6>")
		)
		(pad "261" smd rect
			(at 2.050034 40.375078 270)
			(size 0.519938 1.4986)
			(layers "F.Cu" "F.Mask" "F.Paste")
			(net "M_B_CPU0_SB_DQS_DP<6>")
		)
		(pad "262" smd rect
			(at 2.050034 41.224962 270)
			(size 0.519938 1.4986)
			(layers "F.Cu" "F.Mask" "F.Paste")
			(net "GND")
		)
		(pad "263" smd rect
			(at 2.050034 42.0751 270)
			(size 0.519938 1.4986)
			(layers "F.Cu" "F.Mask" "F.Paste")
			(net "M_B_CPU0_SB_DQ<14>")
		)
		(pad "264" smd rect
			(at 2.050034 42.924984 270)
			(size 0.519938 1.4986)
			(layers "F.Cu" "F.Mask" "F.Paste")
			(net "GND")
		)
		(pad "265" smd rect
			(at 2.050034 43.775122 270)
			(size 0.519938 1.4986)
			(layers "F.Cu" "F.Mask" "F.Paste")
			(net "M_B_CPU0_SB_DQ<15>")
		)
		(pad "266" smd rect
			(at 2.050034 44.625006 270)
			(size 0.519938 1.4986)
			(layers "F.Cu" "F.Mask" "F.Paste")
			(net "GND")
		)
		(pad "267" smd rect
			(at 2.050034 45.47489 270)
			(size 0.519938 1.4986)
			(layers "F.Cu" "F.Mask" "F.Paste")
			(net "M_B_CPU0_SB_DQ<18>")
		)
		(pad "268" smd rect
			(at 2.050034 46.325028 270)
			(size 0.519938 1.4986)
			(layers "F.Cu" "F.Mask" "F.Paste")
			(net "GND")
		)
		(pad "269" smd rect
			(at 2.050034 47.174912 270)
			(size 0.519938 1.4986)
			(layers "F.Cu" "F.Mask" "F.Paste")
			(net "M_B_CPU0_SB_DQ<19>")
		)
		(pad "270" smd rect
			(at 2.050034 48.02505 270)
			(size 0.519938 1.4986)
			(layers "F.Cu" "F.Mask" "F.Paste")
			(net "GND")
		)
		(pad "271" smd rect
			(at 2.050034 48.874934 270)
			(size 0.519938 1.4986)
			(layers "F.Cu" "F.Mask" "F.Paste")
			(net "M_B_CPU0_SB_DQS_DN<7>")
		)
		(pad "272" smd rect
			(at 2.050034 49.725072 270)
			(size 0.519938 1.4986)
			(layers "F.Cu" "F.Mask" "F.Paste")
			(net "M_B_CPU0_SB_DQS_DP<7>")
		)
		(pad "273" smd rect
			(at 2.050034 50.574956 270)
			(size 0.519938 1.4986)
			(layers "F.Cu" "F.Mask" "F.Paste")
			(net "GND")
		)
		(pad "274" smd rect
			(at 2.050034 51.425094 270)
			(size 0.519938 1.4986)
			(layers "F.Cu" "F.Mask" "F.Paste")
			(net "M_B_CPU0_SB_DQ<22>")
		)
	)
)
